(kicad_pcb
	(version 20260206)
	(generator "pcbnew")
	(generator_version "10.0")
	(general
		(thickness 1.6)
		(legacy_teardrops no)
	)
	(paper "A4")
	(title_block
		(title "Bryce Canyon_IOM_M2_16342-2_OCP.brd")
		(comment 1 "Bryce Canyon / footprints 806-812 of 1146")
	)
	(layers
		(0 "F.Cu" signal "TOP")
		(4 "In1.Cu" signal "L2GND")
		(6 "In2.Cu" signal "L3")
		(8 "In3.Cu" signal "L4VCC")
		(10 "In4.Cu" signal "L5VCC")
		(12 "In5.Cu" signal "L6")
		(14 "In6.Cu" signal "L7GND")
		(2 "B.Cu" signal "BOTTOM")
		(9 "F.Adhes" user "F.Adhesive")
		(11 "B.Adhes" user "B.Adhesive")
		(13 "F.Paste" user "Package Geometry/Pastemask Top")
		(15 "B.Paste" user "Package Geometry/Pastemask Bottom")
		(5 "F.SilkS" user "Ref Des/Silkscreen Top")
		(7 "B.SilkS" user "Ref Des/Silkscreen Bottom")
		(1 "F.Mask" user "Board Geometry/Soldermask Top")
		(3 "B.Mask" user "Board Geometry/Soldermask Bottom")
		(17 "Dwgs.User" user "User.Drawings")
		(19 "Cmts.User" user "User.Comments")
		(21 "Eco1.User" user "User.Eco1")
		(23 "Eco2.User" user "User.Eco2")
		(25 "Edge.Cuts" user "Board Geometry/Outline")
		(27 "Margin" user)
		(31 "F.CrtYd" user "Package Geometry/Place Bound Top")
		(29 "B.CrtYd" user "Package Geometry/Place Bound Bottom")
		(35 "F.Fab" user "Ref Des/Assembly Top")
		(33 "B.Fab" user "Ref Des/Assembly Bottom")
	)
	(footprint ""
		(layer "B.Cu")
		(at 84.900008 -150.406862 -90)
		(property "Reference" "U15"
			(at 0 0 90)
			(layer "B.SilkS")
			(hide yes)
			(effects
				(font
					(size 1.27 1.27)
				)
				(justify mirror)
			)
		)
		(property "Value" "NX3L1G66GW-GP"
			(at 2.3368 -8.6868 270)
			(unlocked yes)
			(layer "B.Fab")
			(hide yes)
			(effects
				(font
					(size 1.016 1.016)
					(thickness 0.1524)
				)
				(justify mirror)
			)
		)
		(property "Device Type" "SC70-5H44"
			(at 2.3114 -10.414 270)
			(unlocked yes)
			(layer "B.Fab")
			(hide yes)
			(effects
				(font
					(size 1.016 1.016)
					(thickness 0.1524)
				)
				(justify mirror)
			)
		)
		(duplicate_pad_numbers_are_jumpers no)
		(fp_line
			(start -1.27 1.7018)
			(end 1.27 1.7018)
			(stroke
				(width 0.1524)
				(type default)
			)
			(layer "B.SilkS")
		)
		(fp_line
			(start 1.27 1.7018)
			(end 1.27 -1.7018)
			(stroke
				(width 0.1524)
				(type default)
			)
			(layer "B.SilkS")
		)
		(fp_line
			(start -1.27 -1.7018)
			(end -1.27 1.7018)
			(stroke
				(width 0.1524)
				(type default)
			)
			(layer "B.SilkS")
		)
		(fp_line
			(start 1.27 -1.7018)
			(end -1.27 -1.7018)
			(stroke
				(width 0.1524)
				(type default)
			)
			(layer "B.SilkS")
		)
		(fp_line
			(start -1.3843 -1.8034)
			(end -1.3843 -1.1176)
			(stroke
				(width 0.3302)
				(type default)
			)
			(layer "B.SilkS")
		)
		(fp_line
			(start -0.6604 -1.8034)
			(end -1.3843 -1.8034)
			(stroke
				(width 0.3302)
				(type default)
			)
			(layer "B.SilkS")
		)
		(fp_rect
			(start 1.524 1.9558)
			(end -1.524 -1.9558)
			(stroke
				(width 0)
				(type default)
			)
			(fill no)
			(layer "B.CrtYd")
		)
		(fp_poly
			(pts
				(xy 1.524 -1.9558) (xy -1.524 -1.9558) (xy -1.524 1.9558) (xy 1.524 1.9558)
			)
			(stroke
				(width 0)
				(type default)
			)
			(fill no)
			(layer "B.Fab")
		)
		(pad "1" smd rect
			(at -0.65024 -0.8255 90)
			(size 0.4064 1.2192)
			(layers "B.Cu" "B.Mask" "B.Paste")
			(net "I2C_BMC_COMP_SDA_R")
		)
		(pad "2" smd rect
			(at 0 -0.8255 90)
			(size 0.4064 1.2192)
			(layers "B.Cu" "B.Mask" "B.Paste")
			(net "I2C_BMC_COMP_SDA_OUT")
		)
		(pad "3" smd rect
			(at 0.65024 -0.8255 90)
			(size 0.4064 1.2192)
			(layers "B.Cu" "B.Mask" "B.Paste")
			(net "GND")
		)
		(pad "4" smd rect
			(at 0.65024 0.8255 90)
			(size 0.4064 1.2192)
			(layers "B.Cu" "B.Mask" "B.Paste")
			(net "COMP_PWR_EN")
		)
		(pad "5" smd rect
			(at -0.65024 0.8255 90)
			(size 0.4064 1.2192)
			(layers "B.Cu" "B.Mask" "B.Paste")
			(net "P3V3_STBY")
		)
	)
	(footprint ""
		(layer "B.Cu")
		(at 12.091924 -133.85673 90)
		(property "Reference" "R243"
			(at 0 0 90)
			(layer "B.SilkS")
			(hide yes)
			(effects
				(font
					(size 1.27 1.27)
				)
				(justify mirror)
			)
		)
		(property "Value" "120R2F-GP"
			(at -0.064008 -3.993896 90)
			(unlocked yes)
			(layer "B.Fab")
			(hide yes)
			(effects
				(font
					(size 1.016 1.016)
					(thickness 0.1524)
				)
				(justify mirror)
			)
		)
		(property "Device Type" "R402H16"
			(at -0.064008 -5.517896 90)
			(unlocked yes)
			(layer "B.Fab")
			(hide yes)
			(effects
				(font
					(size 1.016 1.016)
					(thickness 0.1524)
				)
				(justify mirror)
			)
		)
		(duplicate_pad_numbers_are_jumpers no)
		(fp_line
			(start 0.508 -0.9398)
			(end 0.508 0.9398)
			(stroke
				(width 0.1524)
				(type default)
			)
			(layer "B.SilkS")
		)
		(fp_line
			(start -0.508 -0.9398)
			(end 0.508 -0.9398)
			(stroke
				(width 0.1524)
				(type default)
			)
			(layer "B.SilkS")
		)
		(fp_rect
			(start 0.508 0.9398)
			(end -0.508 -0.9398)
			(stroke
				(width 0)
				(type default)
			)
			(fill no)
			(layer "B.CrtYd")
		)
		(fp_rect
			(start 0.508 0.9398)
			(end -0.508 -0.9398)
			(stroke
				(width 0)
				(type default)
			)
			(fill no)
			(layer "B.Fab")
		)
		(pad "1" smd custom
			(at 0 -0.4445 270)
			(size 0.1397 0.1397)
			(layers "B.Cu" "B.Mask" "B.Paste")
			(net "MEMA_4")
			(options
				(clearance outline)
				(anchor circle)
			)
			(primitives
				(gr_poly
					(pts
						(arc
							(start -0.1778 0.2794)
							(mid -0.249642 0.249642)
							(end -0.2794 0.1778)
						)
						(arc
							(start -0.2794 -0.1778)
							(mid -0.249642 -0.249642)
							(end -0.1778 -0.2794)
						)
						(arc
							(start 0.1778 -0.2794)
							(mid 0.249642 -0.249642)
							(end 0.2794 -0.1778)
						)
						(arc
							(start 0.2794 0.1778)
							(mid 0.249642 0.249642)
							(end 0.1778 0.2794)
						)
					)
					(width 0)
					(fill yes)
				)
			)
		)
		(pad "2" smd custom
			(at 0 0.4445 270)
			(size 0.1397 0.1397)
			(layers "B.Cu" "B.Mask" "B.Paste")
			(net "P1V2_STBY")
			(options
				(clearance outline)
				(anchor circle)
			)
			(primitives
				(gr_poly
					(pts
						(arc
							(start -0.1778 0.2794)
							(mid -0.249642 0.249642)
							(end -0.2794 0.1778)
						)
						(arc
							(start -0.2794 -0.1778)
							(mid -0.249642 -0.249642)
							(end -0.1778 -0.2794)
						)
						(arc
							(start 0.1778 -0.2794)
							(mid 0.249642 -0.249642)
							(end 0.2794 -0.1778)
						)
						(arc
							(start 0.2794 0.1778)
							(mid 0.249642 0.249642)
							(end 0.1778 0.2794)
						)
					)
					(width 0)
					(fill yes)
				)
			)
		)
	)
	(footprint ""
		(layer "B.Cu")
		(at 55.746142 -135.603742)
		(property "Reference" "R169"
			(at 0 0 0)
			(layer "B.SilkS")
			(hide yes)
			(effects
				(font
					(size 1.27 1.27)
				)
				(justify mirror)
			)
		)
		(property "Value" "0R2J-2-GP"
			(at -0.064008 -3.993896 0)
			(unlocked yes)
			(layer "B.Fab")
			(hide yes)
			(effects
				(font
					(size 1.016 1.016)
					(thickness 0.1524)
				)
				(justify mirror)
			)
		)
		(property "Device Type" "R402H16"
			(at -0.064008 -5.517896 0)
			(unlocked yes)
			(layer "B.Fab")
			(hide yes)
			(effects
				(font
					(size 1.016 1.016)
					(thickness 0.1524)
				)
				(justify mirror)
			)
		)
		(duplicate_pad_numbers_are_jumpers no)
		(fp_line
			(start -0.508 -0.9398)
			(end 0.508 -0.9398)
			(stroke
				(width 0.1524)
				(type default)
			)
			(layer "B.SilkS")
		)
		(fp_line
			(start 0.508 -0.9398)
			(end 0.508 0.9398)
			(stroke
				(width 0.1524)
				(type default)
			)
			(layer "B.SilkS")
		)
		(fp_rect
			(start 0.508 0.9398)
			(end -0.508 -0.9398)
			(stroke
				(width 0)
				(type default)
			)
			(fill no)
			(layer "B.CrtYd")
		)
		(fp_rect
			(start 0.508 0.9398)
			(end -0.508 -0.9398)
			(stroke
				(width 0)
				(type default)
			)
			(fill no)
			(layer "B.Fab")
		)
		(pad "1" smd custom
			(at 0 -0.4445 180)
			(size 0.1397 0.1397)
			(layers "B.Cu" "B.Mask" "B.Paste")
			(net "COMP_PWR_BTN_R_N")
			(options
				(clearance outline)
				(anchor circle)
			)
			(primitives
				(gr_poly
					(pts
						(arc
							(start -0.1778 0.2794)
							(mid -0.249642 0.249642)
							(end -0.2794 0.1778)
						)
						(arc
							(start -0.2794 -0.1778)
							(mid -0.249642 -0.249642)
							(end -0.1778 -0.2794)
						)
						(arc
							(start 0.1778 -0.2794)
							(mid 0.249642 -0.249642)
							(end 0.2794 -0.1778)
						)
						(arc
							(start 0.2794 0.1778)
							(mid 0.249642 0.249642)
							(end 0.1778 0.2794)
						)
					)
					(width 0)
					(fill yes)
				)
			)
		)
		(pad "2" smd custom
			(at 0 0.4445 180)
			(size 0.1397 0.1397)
			(layers "B.Cu" "B.Mask" "B.Paste")
			(net "COMP_PWR_BTN_N")
			(options
				(clearance outline)
				(anchor circle)
			)
			(primitives
				(gr_poly
					(pts
						(arc
							(start -0.1778 0.2794)
							(mid -0.249642 0.249642)
							(end -0.2794 0.1778)
						)
						(arc
							(start -0.2794 -0.1778)
							(mid -0.249642 -0.249642)
							(end -0.1778 -0.2794)
						)
						(arc
							(start 0.1778 -0.2794)
							(mid 0.249642 -0.249642)
							(end 0.2794 -0.1778)
						)
						(arc
							(start 0.2794 0.1778)
							(mid 0.249642 0.249642)
							(end 0.1778 0.2794)
						)
					)
					(width 0)
					(fill yes)
				)
			)
		)
	)
	(footprint ""
		(layer "B.Cu")
		(at 68.506086 -142.776702 180)
		(property "Reference" "R159"
			(at 0 0 0)
			(layer "B.SilkS")
			(hide yes)
			(effects
				(font
					(size 1.27 1.27)
				)
				(justify mirror)
			)
		)
		(property "Value" "0R2J-2-GP"
			(at -0.064008 -3.993896 180)
			(unlocked yes)
			(layer "B.Fab")
			(hide yes)
			(effects
				(font
					(size 1.016 1.016)
					(thickness 0.1524)
				)
				(justify mirror)
			)
		)
		(property "Device Type" "R402H16"
			(at -0.064008 -5.517896 180)
			(unlocked yes)
			(layer "B.Fab")
			(hide yes)
			(effects
				(font
					(size 1.016 1.016)
					(thickness 0.1524)
				)
				(justify mirror)
			)
		)
		(duplicate_pad_numbers_are_jumpers no)
		(fp_line
			(start 0.508 -0.9398)
			(end 0.508 0.9398)
			(stroke
				(width 0.1524)
				(type default)
			)
			(layer "B.SilkS")
		)
		(fp_line
			(start -0.508 -0.9398)
			(end 0.508 -0.9398)
			(stroke
				(width 0.1524)
				(type default)
			)
			(layer "B.SilkS")
		)
		(fp_rect
			(start 0.508 0.9398)
			(end -0.508 -0.9398)
			(stroke
				(width 0)
				(type default)
			)
			(fill no)
			(layer "B.CrtYd")
		)
		(fp_rect
			(start 0.508 0.9398)
			(end -0.508 -0.9398)
			(stroke
				(width 0)
				(type default)
			)
			(fill no)
			(layer "B.Fab")
		)
		(pad "1" smd custom
			(at 0 -0.4445)
			(size 0.1397 0.1397)
			(layers "B.Cu" "B.Mask" "B.Paste")
			(net "BMC_SMB12_CLK")
			(options
				(clearance outline)
				(anchor circle)
			)
			(primitives
				(gr_poly
					(pts
						(arc
							(start -0.1778 0.2794)
							(mid -0.249642 0.249642)
							(end -0.2794 0.1778)
						)
						(arc
							(start -0.2794 -0.1778)
							(mid -0.249642 -0.249642)
							(end -0.1778 -0.2794)
						)
						(arc
							(start 0.1778 -0.2794)
							(mid 0.249642 -0.249642)
							(end 0.2794 -0.1778)
						)
						(arc
							(start 0.2794 0.1778)
							(mid 0.249642 0.249642)
							(end 0.1778 0.2794)
						)
					)
					(width 0)
					(fill yes)
				)
			)
		)
		(pad "2" smd custom
			(at 0 0.4445)
			(size 0.1397 0.1397)
			(layers "B.Cu" "B.Mask" "B.Paste")
			(net "I2C_DEBUG_SCL_L")
			(options
				(clearance outline)
				(anchor circle)
			)
			(primitives
				(gr_poly
					(pts
						(arc
							(start -0.1778 0.2794)
							(mid -0.249642 0.249642)
							(end -0.2794 0.1778)
						)
						(arc
							(start -0.2794 -0.1778)
							(mid -0.249642 -0.249642)
							(end -0.1778 -0.2794)
						)
						(arc
							(start 0.1778 -0.2794)
							(mid 0.249642 -0.249642)
							(end 0.2794 -0.1778)
						)
						(arc
							(start 0.2794 0.1778)
							(mid 0.249642 0.249642)
							(end 0.1778 0.2794)
						)
					)
					(width 0)
					(fill yes)
				)
			)
		)
	)
	(footprint ""
		(layer "B.Cu")
		(at 43.129454 -119.168672 -90)
		(property "Reference" "R342"
			(at 0 0 90)
			(layer "B.SilkS")
			(hide yes)
			(effects
				(font
					(size 1.27 1.27)
				)
				(justify mirror)
			)
		)
		(property "Value" "0R2J-2-GP"
			(at -0.064008 -3.993896 270)
			(unlocked yes)
			(layer "B.Fab")
			(hide yes)
			(effects
				(font
					(size 1.016 1.016)
					(thickness 0.1524)
				)
				(justify mirror)
			)
		)
		(property "Device Type" "R402H16"
			(at -0.064008 -5.517896 270)
			(unlocked yes)
			(layer "B.Fab")
			(hide yes)
			(effects
				(font
					(size 1.016 1.016)
					(thickness 0.1524)
				)
				(justify mirror)
			)
		)
		(duplicate_pad_numbers_are_jumpers no)
		(fp_line
			(start -0.508 -0.9398)
			(end 0.508 -0.9398)
			(stroke
				(width 0.1524)
				(type default)
			)
			(layer "B.SilkS")
		)
		(fp_line
			(start 0.508 -0.9398)
			(end 0.508 0.9398)
			(stroke
				(width 0.1524)
				(type default)
			)
			(layer "B.SilkS")
		)
		(fp_rect
			(start 0.508 0.9398)
			(end -0.508 -0.9398)
			(stroke
				(width 0)
				(type default)
			)
			(fill no)
			(layer "B.CrtYd")
		)
		(fp_rect
			(start 0.508 0.9398)
			(end -0.508 -0.9398)
			(stroke
				(width 0)
				(type default)
			)
			(fill no)
			(layer "B.Fab")
		)
		(pad "1" smd custom
			(at 0 -0.4445 90)
			(size 0.1397 0.1397)
			(layers "B.Cu" "B.Mask" "B.Paste")
			(net "TEMP_3_SDA")
			(options
				(clearance outline)
				(anchor circle)
			)
			(primitives
				(gr_poly
					(pts
						(arc
							(start -0.1778 0.2794)
							(mid -0.249642 0.249642)
							(end -0.2794 0.1778)
						)
						(arc
							(start -0.2794 -0.1778)
							(mid -0.249642 -0.249642)
							(end -0.1778 -0.2794)
						)
						(arc
							(start 0.1778 -0.2794)
							(mid 0.249642 -0.249642)
							(end 0.2794 -0.1778)
						)
						(arc
							(start 0.2794 0.1778)
							(mid 0.249642 0.249642)
							(end 0.1778 0.2794)
						)
					)
					(width 0)
					(fill yes)
				)
			)
		)
		(pad "2" smd custom
			(at 0 0.4445 90)
			(size 0.1397 0.1397)
			(layers "B.Cu" "B.Mask" "B.Paste")
			(net "I2C_IOM_SDA")
			(options
				(clearance outline)
				(anchor circle)
			)
			(primitives
				(gr_poly
					(pts
						(arc
							(start -0.1778 0.2794)
							(mid -0.249642 0.249642)
							(end -0.2794 0.1778)
						)
						(arc
							(start -0.2794 -0.1778)
							(mid -0.249642 -0.249642)
							(end -0.1778 -0.2794)
						)
						(arc
							(start 0.1778 -0.2794)
							(mid 0.249642 -0.249642)
							(end 0.2794 -0.1778)
						)
						(arc
							(start 0.2794 0.1778)
							(mid 0.249642 0.249642)
							(end 0.1778 0.2794)
						)
					)
					(width 0)
					(fill yes)
				)
			)
		)
	)
	(footprint ""
		(layer "B.Cu")
		(at 80.345788 -153.995882 90)
		(property "Reference" "R100"
			(at 0 0 90)
			(layer "B.SilkS")
			(hide yes)
			(effects
				(font
					(size 1.27 1.27)
				)
				(justify mirror)
			)
		)
		(property "Value" "0R2J-2-GP"
			(at -0.064008 -3.993896 90)
			(unlocked yes)
			(layer "B.Fab")
			(hide yes)
			(effects
				(font
					(size 1.016 1.016)
					(thickness 0.1524)
				)
				(justify mirror)
			)
		)
		(property "Device Type" "R402H16"
			(at -0.064008 -5.517896 90)
			(unlocked yes)
			(layer "B.Fab")
			(hide yes)
			(effects
				(font
					(size 1.016 1.016)
					(thickness 0.1524)
				)
				(justify mirror)
			)
		)
		(duplicate_pad_numbers_are_jumpers no)
		(fp_line
			(start 0.508 -0.9398)
			(end 0.508 0.9398)
			(stroke
				(width 0.1524)
				(type default)
			)
			(layer "B.SilkS")
		)
		(fp_line
			(start -0.508 -0.9398)
			(end 0.508 -0.9398)
			(stroke
				(width 0.1524)
				(type default)
			)
			(layer "B.SilkS")
		)
		(fp_rect
			(start 0.508 0.9398)
			(end -0.508 -0.9398)
			(stroke
				(width 0)
				(type default)
			)
			(fill no)
			(layer "B.CrtYd")
		)
		(fp_rect
			(start 0.508 0.9398)
			(end -0.508 -0.9398)
			(stroke
				(width 0)
				(type default)
			)
			(fill no)
			(layer "B.Fab")
		)
		(pad "1" smd custom
			(at 0 -0.4445 270)
			(size 0.1397 0.1397)
			(layers "B.Cu" "B.Mask" "B.Paste")
			(net "I2C_BMC_COMP_ALERT_N_R")
			(options
				(clearance outline)
				(anchor circle)
			)
			(primitives
				(gr_poly
					(pts
						(arc
							(start -0.1778 0.2794)
							(mid -0.249642 0.249642)
							(end -0.2794 0.1778)
						)
						(arc
							(start -0.2794 -0.1778)
							(mid -0.249642 -0.249642)
							(end -0.1778 -0.2794)
						)
						(arc
							(start 0.1778 -0.2794)
							(mid 0.249642 -0.249642)
							(end 0.2794 -0.1778)
						)
						(arc
							(start 0.2794 0.1778)
							(mid 0.249642 0.249642)
							(end 0.1778 0.2794)
						)
					)
					(width 0)
					(fill yes)
				)
			)
		)
		(pad "2" smd custom
			(at 0 0.4445 270)
			(size 0.1397 0.1397)
			(layers "B.Cu" "B.Mask" "B.Paste")
			(net "I2C_BMC_COMP_ALERT_N")
			(options
				(clearance outline)
				(anchor circle)
			)
			(primitives
				(gr_poly
					(pts
						(arc
							(start -0.1778 0.2794)
							(mid -0.249642 0.249642)
							(end -0.2794 0.1778)
						)
						(arc
							(start -0.2794 -0.1778)
							(mid -0.249642 -0.249642)
							(end -0.1778 -0.2794)
						)
						(arc
							(start 0.1778 -0.2794)
							(mid 0.249642 -0.249642)
							(end 0.2794 -0.1778)
						)
						(arc
							(start 0.2794 0.1778)
							(mid 0.249642 0.249642)
							(end 0.1778 0.2794)
						)
					)
					(width 0)
					(fill yes)
				)
			)
		)
	)
	(footprint ""
		(layer "B.Cu")
		(at 48.690276 -135.719312)
		(property "Reference" "R142"
			(at 0 0 0)
			(layer "B.SilkS")
			(hide yes)
			(effects
				(font
					(size 1.27 1.27)
				)
				(justify mirror)
			)
		)
		(property "Value" "200R2F-L-GP"
			(at -0.064008 -3.993896 0)
			(unlocked yes)
			(layer "B.Fab")
			(hide yes)
			(effects
				(font
					(size 1.016 1.016)
					(thickness 0.1524)
				)
				(justify mirror)
			)
		)
		(property "Device Type" "R402H16"
			(at -0.064008 -5.517896 0)
			(unlocked yes)
			(layer "B.Fab")
			(hide yes)
			(effects
				(font
					(size 1.016 1.016)
					(thickness 0.1524)
				)
				(justify mirror)
			)
		)
		(duplicate_pad_numbers_are_jumpers no)
		(fp_line
			(start -0.508 -0.9398)
			(end 0.508 -0.9398)
			(stroke
				(width 0.1524)
				(type default)
			)
			(layer "B.SilkS")
		)
		(fp_line
			(start 0.508 -0.9398)
			(end 0.508 0.9398)
			(stroke
				(width 0.1524)
				(type default)
			)
			(layer "B.SilkS")
		)
		(fp_rect
			(start 0.508 0.9398)
			(end -0.508 -0.9398)
			(stroke
				(width 0)
				(type default)
			)
			(fill no)
			(layer "B.CrtYd")
		)
		(fp_rect
			(start 0.508 0.9398)
			(end -0.508 -0.9398)
			(stroke
				(width 0)
				(type default)
			)
			(fill no)
			(layer "B.Fab")
		)
		(pad "1" smd custom
			(at 0 -0.4445 180)
			(size 0.1397 0.1397)
			(layers "B.Cu" "B.Mask" "B.Paste")
			(net "BMC_PEREXT")
			(options
				(clearance outline)
				(anchor circle)
			)
			(primitives
				(gr_poly
					(pts
						(arc
							(start -0.1778 0.2794)
							(mid -0.249642 0.249642)
							(end -0.2794 0.1778)
						)
						(arc
							(start -0.2794 -0.1778)
							(mid -0.249642 -0.249642)
							(end -0.1778 -0.2794)
						)
						(arc
							(start 0.1778 -0.2794)
							(mid 0.249642 -0.249642)
							(end 0.2794 -0.1778)
						)
						(arc
							(start 0.2794 0.1778)
							(mid 0.249642 0.249642)
							(end 0.1778 0.2794)
						)
					)
					(width 0)
					(fill yes)
				)
			)
		)
		(pad "2" smd custom
			(at 0 0.4445 180)
			(size 0.1397 0.1397)
			(layers "B.Cu" "B.Mask" "B.Paste")
			(net "GND")
			(options
				(clearance outline)
				(anchor circle)
			)
			(primitives
				(gr_poly
					(pts
						(arc
							(start -0.1778 0.2794)
							(mid -0.249642 0.249642)
							(end -0.2794 0.1778)
						)
						(arc
							(start -0.2794 -0.1778)
							(mid -0.249642 -0.249642)
							(end -0.1778 -0.2794)
						)
						(arc
							(start 0.1778 -0.2794)
							(mid 0.249642 -0.249642)
							(end 0.2794 -0.1778)
						)
						(arc
							(start 0.2794 0.1778)
							(mid 0.249642 0.249642)
							(end 0.1778 0.2794)
						)
					)
					(width 0)
					(fill yes)
				)
			)
		)
	)
)
